G04 ================== begin FILE IDENTIFICATION RECORD ==================*
G04 Layout Name:  D:/<user>/Wistron_project/16318-2/gbr/16318-2.brd*
G04 Film Name:    DP_REF_L3*
G04 File Format:  Gerber RS274X*
G04 File Origin:  Cadence Allegro 16.5-S056*
G04 Origin Date:  Mon Aug 07 11:09:58 2017*
G04 *
G04 Layer:  BOARD GEOMETRY/DP_REF_L3_TBL*
G04 Layer:  BOARD GEOMETRY/DP_REF_L3_L3*
G04 Layer:  BOARD GEOMETRY/PANEL_OUTLINE*
G04 *
G04 Offset:    (0.00 0.00)*
G04 Mirror:    No*
G04 Mode:      Positive*
G04 Rotation:  0*
G04 FullContactRelief:  No*
G04 UndefLineWidth:     6.00*
G04 ================== end FILE IDENTIFICATION RECORD ====================*
%FSLAX35Y35*MOIN*%
%IR0*IPPOS*OFA0.00000B0.00000*MIA0B0*SFA1.00000B1.00000*%
%ADD10C,.02*%
%ADD11C,.004*%
%ADD12C,.006*%
%ADD13C,.0055*%
G75*
%LPD*%
G75*
G54D10*
G01X975497Y625480D02*
X1762997D01*
G01X975497Y729430D02*
Y625480D01*
G01Y694780D02*
X1762997D01*
G01X975497Y660130D02*
X1762997D01*
G01X975497Y729430D02*
X1762997D01*
G01X1150497D02*
Y625480D01*
G01X1447997Y729430D02*
Y625480D01*
G01X1552997Y729430D02*
Y625480D01*
G01X1762997Y729430D02*
Y625480D01*
G54D11*
G01X81936Y562222D02*
G02X76818I-2559J0D01*
G01D02*
Y572749D01*
G01X77286Y574518D02*
G02X78018Y572748I-1770J-1768D01*
G01X76437Y573668D02*
G03X75518Y574048I-919J-921D01*
G01X76818Y572749D02*
G03X76437Y573669I-1302J0D01*
G01X75518Y575248D02*
G02X77286Y574518I2J-2502D01*
G01X76437Y573668D02*
G03X75518Y574048I-919J-921D01*
G01X76818Y572749D02*
G03X76437Y573669I-1302J0D01*
G01X74737Y575248D02*
X75518D01*
G01Y574048D02*
X74737D01*
G01X72555Y574345D02*
G02X74737Y575248I2181J-2183D01*
G01Y574048D02*
G03X73404Y573496I0J-1886D01*
G01X71554Y571996D02*
G02X72506Y574296I3252J1D01*
G01X73355Y573447D02*
G03X72754Y571996I1451J-1451D01*
G01X71554Y568898D02*
Y571996D01*
G01X72754D02*
Y568569D01*
G01Y571996D02*
Y568569D01*
G01X71554Y568898D02*
Y571996D01*
G01X73355Y573447D02*
G03X72754Y571996I1451J-1451D01*
G01X71554D02*
G02X72506Y574296I3252J1D01*
G01X74737Y574048D02*
G03X73404Y573496I0J-1886D01*
G01X72555Y574345D02*
G02X74737Y575248I2181J-2183D01*
G01X75518Y574048D02*
X74737D01*
G01Y575248D02*
X75518D01*
G01X76437Y573668D02*
G03X75518Y574048I-919J-921D01*
G01X77286Y574518D02*
G02X78018Y572748I-1770J-1768D01*
G01X75518Y575248D02*
G02X77286Y574518I2J-2502D01*
G01X76818Y572749D02*
G03X76437Y573669I-1302J0D01*
G01X77286Y574518D02*
G02X78018Y572748I-1770J-1768D01*
G01X75518Y575248D02*
G02X77286Y574518I2J-2502D01*
G01X76818Y562222D02*
Y572749D01*
G01X81936Y562222D02*
G02X76818I-2559J0D01*
G01X93871Y584142D02*
X88410D01*
G01Y585342D02*
X93871D01*
G01Y590601D02*
G02Y584142I0J-3229D01*
G01Y585342D02*
G03Y589401I0J2030D01*
G01X84327Y590601D02*
X93871D01*
G01Y589401D02*
X84327D01*
G01Y593986D02*
G03Y590601I0J-1692D01*
G01Y589401D02*
G02Y595186I0J2893D01*
G01X103183Y590899D02*
G02X100393Y593116I0J2864D01*
G01X101562Y593387D02*
G03X103183Y592099I1621J376D01*
G01X105496Y592484D02*
G02X103183Y590899I-2313J895D01*
G01Y592099D02*
G03X104376Y592917I0J1279D01*
G01X108642Y592641D02*
G03X105496Y592484I-1535J-836D01*
G01X111186Y590932D02*
G02X108642Y592641I0J2748D01*
G01X111186Y592132D02*
G03X112628Y593237I0J1493D01*
G01X109769Y593056D02*
G03X111186Y592132I1417J625D01*
G01X113788Y592925D02*
G02X111186Y590932I-2602J702D01*
G01Y592132D02*
G03X112628Y593237I0J1493D01*
G01X109769Y593056D02*
G03X111186Y592132I1417J625D01*
G01X140090Y591123D02*
Y596157D01*
G01X141290D02*
Y591123D01*
G01X142800Y588413D02*
G02X140090Y591123I0J2710D01*
G01X141290D02*
G03X142800Y589613I1510J0D01*
G01X143470Y588413D02*
X142800D01*
G01Y589613D02*
X143469D01*
G01X142800D02*
X143469D01*
G01X143470Y588413D02*
X142800D01*
G01X141290Y591123D02*
G03X142800Y589613I1510J0D01*
G01Y588413D02*
G02X140090Y591123I0J2710D01*
G01X141290Y596157D02*
Y591123D01*
G01X140090D02*
Y596157D01*
G01X111186Y592132D02*
G03X112628Y593237I0J1493D01*
G01X111186Y590932D02*
G02X108642Y592641I0J2748D01*
G01X113788Y592925D02*
G02X111186Y590932I-2602J702D01*
G01X109769Y593056D02*
G03X111186Y592132I1417J625D01*
G01Y590932D02*
G02X108642Y592641I0J2748D01*
G01X113788Y592925D02*
G02X111186Y590932I-2602J702D01*
G01X108642Y592641D02*
G03X105496Y592484I-1535J-836D01*
G01X103183Y592099D02*
G03X104376Y592917I0J1279D01*
G01X105496Y592484D02*
G02X103183Y590899I-2313J895D01*
G01X101562Y593387D02*
G03X103183Y592099I1621J376D01*
G01Y590899D02*
G02X100393Y593116I0J2864D01*
G01X84327Y589401D02*
G02Y595186I0J2893D01*
G01Y593986D02*
G03Y590601I0J-1692D01*
G01X93871Y589401D02*
X84327D01*
G01Y590601D02*
X93871D01*
G01Y585342D02*
G03Y589401I0J2030D01*
G01Y590601D02*
G02Y584142I0J-3229D01*
G01X88410Y585342D02*
X93871D01*
G01Y584142D02*
X88410D01*
G01X88507Y557140D02*
X87725D01*
G01X88009Y555940D02*
X87725D01*
G01X89357Y556290D02*
X88507Y557140D01*
G01X88859Y555090D02*
X88009Y555940D01*
G01X90769Y556290D02*
X89357D01*
G01X90770Y555090D02*
X88859D01*
G01X91325Y556521D02*
G02X90769Y556290I-557J556D01*
G01X92174Y555672D02*
G02X90770Y555090I-1405J1405D01*
G01X92756Y557077D02*
G02X92174Y555672I-1987J0D01*
G01X91556Y557077D02*
G02X91325Y556521I-787J1D01*
G01X92174Y555672D02*
G02X90770Y555090I-1405J1405D01*
G01X92756Y557077D02*
G02X92174Y555672I-1987J0D01*
G01X91556Y557612D02*
Y557077D01*
G01X92756Y557612D02*
Y557077D01*
G01X92146Y559186D02*
G03X91556Y557612I1800J-1572D01*
G01X93032Y558375D02*
G03X92756Y557612I914J-762D01*
G01X94044Y559994D02*
G03X92146Y559186I-1J-2631D01*
G01X94044Y558794D02*
G03X93032Y558375I0J-1431D01*
G01X98267Y559994D02*
X94044D01*
G01X98267Y558794D02*
X94044D01*
G01X98832Y560229D02*
G02X98267Y559994I-566J564D01*
G01X99681Y559380D02*
G02X98267Y558794I-1414J1413D01*
G01X106671Y568068D02*
X98832Y560229D01*
G01X107520Y567219D02*
X99681Y559380D01*
G01X108934Y569005D02*
G03X106671Y568068I-1J-3199D01*
G01X108934Y567805D02*
G03X107520Y567219I0J-1999D01*
G01X112619Y569005D02*
X108934D01*
G01X112619Y567805D02*
X108934D01*
G01X113184Y569240D02*
G02X112619Y569005I-566J564D01*
G01X114033Y568391D02*
G02X112619Y567805I-1414J1413D01*
G01X114807Y570863D02*
X113184Y569240D01*
G01X115656Y570014D02*
X114033Y568391D01*
G01X117070Y571800D02*
G03X114807Y570863I-1J-3199D01*
G01X117070Y570600D02*
G03X115656Y570014I0J-1999D01*
G01X120283Y571800D02*
X117070D01*
G01X120259Y570600D02*
X117070D01*
G01X123000Y569027D02*
G03X120283Y571800I-2774J0D01*
G01X121800Y569027D02*
G03X120259Y570600I-1573J0D01*
G01X123000Y568555D02*
Y569027D01*
G01X121800Y568555D02*
Y569027D01*
G01X124344Y567211D02*
G02X123000Y568555I0J1344D01*
G01X124344Y566011D02*
G02X121800Y568555I0J2544D01*
G01X127267Y567211D02*
X124344D01*
G01X127267Y566011D02*
X124344D01*
G01X127777Y567721D02*
G02X127267Y567211I-510J0D01*
G01X128977Y567721D02*
G02X127267Y566011I-1710J0D01*
G01X127777Y568126D02*
Y567721D01*
G01X128977Y568006D02*
Y567721D01*
G01X88009Y555940D02*
X87725D01*
G01X88507Y557140D02*
X87725D01*
G01X88859Y555090D02*
X88009Y555940D01*
G01X89357Y556290D02*
X88507Y557140D01*
G01X90770Y555090D02*
X88859D01*
G01X90769Y556290D02*
X89357D01*
G01X92174Y555672D02*
G02X90770Y555090I-1405J1405D01*
G01X91325Y556521D02*
G02X90769Y556290I-557J556D01*
G01X91556Y557077D02*
G02X91325Y556521I-787J1D01*
G01X92756Y557077D02*
G02X92174Y555672I-1987J0D01*
G01X91325Y556521D02*
G02X90769Y556290I-557J556D01*
G01X91556Y557077D02*
G02X91325Y556521I-787J1D01*
G01X92756Y557612D02*
Y557077D01*
G01X91556Y557612D02*
Y557077D01*
G01X93032Y558375D02*
G03X92756Y557612I914J-762D01*
G01X92146Y559186D02*
G03X91556Y557612I1800J-1572D01*
G01X94044Y558794D02*
G03X93032Y558375I0J-1431D01*
G01X94044Y559994D02*
G03X92146Y559186I-1J-2631D01*
G01X98267Y558794D02*
X94044D01*
G01X98267Y559994D02*
X94044D01*
G01X99681Y559380D02*
G02X98267Y558794I-1414J1413D01*
G01X98832Y560229D02*
G02X98267Y559994I-566J564D01*
G01X107520Y567219D02*
X99681Y559380D01*
G01X106671Y568068D02*
X98832Y560229D01*
G01X108934Y567805D02*
G03X107520Y567219I0J-1999D01*
G01X108934Y569005D02*
G03X106671Y568068I-1J-3199D01*
G01X112619Y567805D02*
X108934D01*
G01X112619Y569005D02*
X108934D01*
G01X114033Y568391D02*
G02X112619Y567805I-1414J1413D01*
G01X113184Y569240D02*
G02X112619Y569005I-566J564D01*
G01X115656Y570014D02*
X114033Y568391D01*
G01X114807Y570863D02*
X113184Y569240D01*
G01X117070Y570600D02*
G03X115656Y570014I0J-1999D01*
G01X117070Y571800D02*
G03X114807Y570863I-1J-3199D01*
G01X120259Y570600D02*
X117070D01*
G01X120283Y571800D02*
X117070D01*
G01X121800Y569027D02*
G03X120259Y570600I-1573J0D01*
G01X123000Y569027D02*
G03X120283Y571800I-2774J0D01*
G01X121800Y568555D02*
Y569027D01*
G01X123000Y568555D02*
Y569027D01*
G01X124344Y566011D02*
G02X121800Y568555I0J2544D01*
G01X124344Y567211D02*
G02X123000Y568555I0J1344D01*
G01X127267Y566011D02*
X124344D01*
G01X127267Y567211D02*
X124344D01*
G01X128977Y567721D02*
G02X127267Y566011I-1710J0D01*
G01X127777Y567721D02*
G02X127267Y567211I-510J0D01*
G01X128977Y568006D02*
Y567721D01*
G01X127777Y568126D02*
Y567721D01*
G01X138204Y578206D02*
X146542D01*
G01Y577006D02*
X138204D01*
G01X135022Y579524D02*
G03X138204Y578206I3182J3182D01*
G01Y577006D02*
G02X134173Y578675I-1J5700D01*
G01X133789Y580757D02*
X135022Y579524D01*
G01X134173Y578675D02*
X132940Y579908D01*
G01X130906Y581950D02*
G02X133789Y580757I2J-4075D01*
G01X132940Y579908D02*
G03X130906Y580750I-2033J-2033D01*
G01X106693Y581950D02*
X130906D01*
G01Y580750D02*
X106694D01*
G01X104312Y580964D02*
G02X106693Y581950I2381J-2382D01*
G01X106694Y580750D02*
G03X105161Y580115I0J-2168D01*
G01X95386Y572039D02*
X104312Y580964D01*
G01X97193Y572147D02*
X96235Y571190D01*
G01X105161Y580115D02*
X97193Y572147D01*
G01X93775Y571371D02*
G03X95386Y572039I-1J2279D01*
G01X96235Y571190D02*
G02X93776Y570171I-2460J2460D01*
G01X82580Y571371D02*
X93775D01*
G01X83141Y570171D02*
X82580D01*
G01X88701D02*
X87501D01*
G01X93776D02*
X93061D01*
G01X80736Y569527D02*
G02X82580Y571371I1844J0D01*
G01Y570171D02*
G03X81936Y569527I0J-644D01*
G01X80736Y562222D02*
Y569527D01*
G01X81936D02*
Y562222D01*
G01X78018D02*
G03X80736I1359J0D01*
G01X78018Y572748D02*
Y562222D01*
G01Y572748D02*
Y562222D01*
G01D02*
G03X80736I1359J0D01*
G01X81936Y569527D02*
Y562222D01*
G01X80736D02*
Y569527D01*
G01X82580Y570171D02*
G03X81936Y569527I0J-644D01*
G01X80736D02*
G02X82580Y571371I1844J0D01*
G01X83141Y570171D02*
X82580D01*
G01Y571371D02*
X93775D01*
G01X88701Y570171D02*
X87501D01*
G01X82580Y571371D02*
X93775D01*
G01X93776Y570171D02*
X93061D01*
G01X82580Y571371D02*
X93775D01*
G01X96235Y571190D02*
G02X93776Y570171I-2460J2460D01*
G01X93775Y571371D02*
G03X95386Y572039I-1J2279D01*
G01X97193Y572147D02*
X96235Y571190D01*
G01X95386Y572039D02*
X104312Y580964D01*
G01X105161Y580115D02*
X97193Y572147D01*
G01X95386Y572039D02*
X104312Y580964D01*
G01X106694Y580750D02*
G03X105161Y580115I0J-2168D01*
G01X104312Y580964D02*
G02X106693Y581950I2381J-2382D01*
G01X130906Y580750D02*
X106694D01*
G01X106693Y581950D02*
X130906D01*
G01X132940Y579908D02*
G03X130906Y580750I-2033J-2033D01*
G01Y581950D02*
G02X133789Y580757I2J-4075D01*
G01X134173Y578675D02*
X132940Y579908D01*
G01X133789Y580757D02*
X135022Y579524D01*
G01X138204Y577006D02*
G02X134173Y578675I-1J5700D01*
G01X135022Y579524D02*
G03X138204Y578206I3182J3182D01*
G01X146542Y577006D02*
X138204D01*
G01Y578206D02*
X146542D01*
G01X98948Y593986D02*
X84327D01*
G01Y595186D02*
X98948D01*
G01X100393Y593116D02*
G03X98948Y593986I-1445J-765D01*
G01Y595186D02*
G02X101455Y593678I1J-2836D01*
G01X104390Y592950D02*
G02X109696Y593215I2717J-1145D01*
G01X115214Y593986D02*
G03X113788Y592925I-41J-1433D01*
G01X112629Y593237D02*
G02X115248Y595186I2544J-684D01*
G01X117291Y593986D02*
X115214D01*
G01X115248Y595186D02*
X117291D01*
G01X119899Y595053D02*
G02X117291Y593986I-2608J2654D01*
G01Y595186D02*
G03X119054Y595906I-1J2520D01*
G01X121138Y596292D02*
X119899Y595053D01*
G01X119054Y595906D02*
X120289Y597141D01*
G01X124128Y597530D02*
G03X121138Y596292I0J-4230D01*
G01X120289Y597141D02*
G02X124127Y598730I3838J-3841D01*
G01X138717Y597530D02*
X124128D01*
G01X124127Y598730D02*
X138717D01*
G01X140090Y596157D02*
G03X138717Y597530I-1373J0D01*
G01Y598730D02*
G02X141290Y596157I0J-2573D01*
G01X138717Y598730D02*
G02X141290Y596157I0J-2573D01*
G01X140090D02*
G03X138717Y597530I-1373J0D01*
G01X124127Y598730D02*
X138717D01*
G01Y597530D02*
X124128D01*
G01X120289Y597141D02*
G02X124127Y598730I3838J-3841D01*
G01X124128Y597530D02*
G03X121138Y596292I0J-4230D01*
G01X119054Y595906D02*
X120289Y597141D01*
G01X121138Y596292D02*
X119899Y595053D01*
G01X117291Y595186D02*
G03X119054Y595906I-1J2520D01*
G01X119899Y595053D02*
G02X117291Y593986I-2608J2654D01*
G01X115248Y595186D02*
X117291D01*
G01Y593986D02*
X115214D01*
G01X112629Y593237D02*
G02X115248Y595186I2544J-684D01*
G01X115214Y593986D02*
G03X113788Y592925I-41J-1433D01*
G01X104390Y592950D02*
G02X109696Y593215I2717J-1145D01*
G01X98948Y595186D02*
G02X101455Y593678I1J-2836D01*
G01X100393Y593116D02*
G03X98948Y593986I-1445J-765D01*
G01X84327Y595186D02*
X98948D01*
G01Y593986D02*
X84327D01*
G54D12*
G01X6250Y-32800D02*
Y-50300D01*
G01X1228Y-32800D02*
X11272D01*
G01X20038Y-50300D02*
Y-32800D01*
G01Y-41258D02*
X21130Y-39800D01*
X22222Y-38925D01*
X23968Y-38634D01*
X25278Y-38925D01*
X26807Y-40092D01*
X27462Y-41842D01*
Y-50300D01*
G01X41250Y-38634D02*
Y-50300D01*
G01Y-33967D02*
X40813Y-33675D01*
Y-33092D01*
X41250Y-32800D01*
X41687Y-33092D01*
Y-33675D01*
X41250Y-33967D01*
G01X55475Y-48259D02*
X56567Y-49425D01*
X58095Y-50300D01*
X59405D01*
X60715Y-49717D01*
X61588Y-48842D01*
X62025Y-47676D01*
X61807Y-45925D01*
X60933Y-45050D01*
X57003Y-43300D01*
X56130Y-41258D01*
X56567Y-39800D01*
X57440Y-38925D01*
X58750Y-38634D01*
X60060Y-38925D01*
X61370Y-39800D01*
G01X90693Y-54675D02*
X92222Y-55842D01*
X93968Y-56133D01*
X95496Y-55842D01*
X96807Y-54384D01*
X97680Y-52342D01*
Y-38634D01*
G01Y-40967D02*
X96807Y-39800D01*
X95496Y-38925D01*
X93968Y-38634D01*
X92222Y-39217D01*
X91130Y-40383D01*
X90256Y-42425D01*
X89820Y-44467D01*
X90038Y-46217D01*
X90912Y-48259D01*
X92222Y-49717D01*
X93968Y-50300D01*
X95278Y-50008D01*
X96807Y-48842D01*
X97680Y-47676D01*
G01X107975Y-42425D02*
X114962D01*
X114307Y-40383D01*
X113215Y-39217D01*
X111687Y-38634D01*
X110158Y-38925D01*
X108848Y-39800D01*
X107975Y-41842D01*
X107538Y-43592D01*
Y-45342D01*
X107975Y-47092D01*
X109067Y-48842D01*
X110377Y-50008D01*
X111905Y-50300D01*
X113433Y-49717D01*
X114962Y-47967D01*
G01X125693Y-50300D02*
Y-38634D01*
G01Y-40967D02*
X126785Y-39800D01*
X127877Y-38925D01*
X129405Y-38634D01*
X130496Y-38925D01*
X131807Y-39800D01*
G01X142320Y-50300D02*
Y-32800D01*
G01Y-41550D02*
X143412Y-39800D01*
X144722Y-38925D01*
X146032Y-38634D01*
X147996Y-39217D01*
X149307Y-40383D01*
X150180Y-42425D01*
Y-44758D01*
X149743Y-47092D01*
X148870Y-48842D01*
X147342Y-50008D01*
X146032Y-50300D01*
X144722Y-50008D01*
X143412Y-49134D01*
X142320Y-47676D01*
G01X160475Y-42425D02*
X167462D01*
X166807Y-40383D01*
X165715Y-39217D01*
X164187Y-38634D01*
X162658Y-38925D01*
X161348Y-39800D01*
X160475Y-41842D01*
X160038Y-43592D01*
Y-45342D01*
X160475Y-47092D01*
X161567Y-48842D01*
X162877Y-50008D01*
X164405Y-50300D01*
X165933Y-49717D01*
X167462Y-47967D01*
G01X178193Y-50300D02*
Y-38634D01*
G01Y-40967D02*
X179285Y-39800D01*
X180377Y-38925D01*
X181905Y-38634D01*
X182996Y-38925D01*
X184307Y-39800D01*
G01X216250Y-38634D02*
Y-50300D01*
G01Y-33967D02*
X215813Y-33675D01*
Y-33092D01*
X216250Y-32800D01*
X216687Y-33092D01*
Y-33675D01*
X216250Y-33967D01*
G01X230475Y-48259D02*
X231567Y-49425D01*
X233095Y-50300D01*
X234405D01*
X235715Y-49717D01*
X236588Y-48842D01*
X237025Y-47676D01*
X236807Y-45925D01*
X235933Y-45050D01*
X232003Y-43300D01*
X231130Y-41258D01*
X231567Y-39800D01*
X232440Y-38925D01*
X233750Y-38634D01*
X235060Y-38925D01*
X236370Y-39800D01*
G01X265256Y-54675D02*
X266785Y-55842D01*
X268095Y-56133D01*
X269842Y-55550D01*
X271152Y-54092D01*
X271807Y-51466D01*
Y-38634D01*
G01Y-33967D02*
X271370Y-33675D01*
Y-33092D01*
X271807Y-32800D01*
X272243Y-33092D01*
Y-33675D01*
X271807Y-33967D01*
G01X282538Y-38634D02*
Y-46800D01*
X283412Y-48842D01*
X284722Y-50008D01*
X286250Y-50300D01*
X287778Y-50008D01*
X289088Y-48842D01*
X289962Y-46800D01*
G01Y-50300D02*
Y-38634D01*
G01X300475Y-48259D02*
X301567Y-49425D01*
X303095Y-50300D01*
X304405D01*
X305715Y-49717D01*
X306588Y-48842D01*
X307025Y-47676D01*
X306807Y-45925D01*
X305933Y-45050D01*
X302003Y-43300D01*
X301130Y-41258D01*
X301567Y-39800D01*
X302440Y-38925D01*
X303750Y-38634D01*
X305060Y-38925D01*
X306370Y-39800D01*
G01X321250Y-32800D02*
Y-50300D01*
G01X318193Y-38634D02*
X324307D01*
G01X354940Y-50300D02*
Y-35425D01*
X355377Y-33967D01*
X356250Y-33092D01*
X357560Y-32800D01*
X358870Y-33383D01*
X359525Y-34842D01*
G01X356905Y-39800D02*
X352538D01*
G01X373750Y-50300D02*
X372440Y-50008D01*
X371130Y-48842D01*
X370256Y-46800D01*
X369820Y-44467D01*
X370256Y-42133D01*
X371130Y-40092D01*
X372440Y-38925D01*
X373750Y-38634D01*
X375060Y-38925D01*
X376370Y-40092D01*
X377243Y-42133D01*
X377462Y-44467D01*
X377243Y-46800D01*
X376370Y-48842D01*
X375060Y-50008D01*
X373750Y-50300D01*
G01X388193D02*
Y-38634D01*
G01Y-40967D02*
X389285Y-39800D01*
X390377Y-38925D01*
X391905Y-38634D01*
X392996Y-38925D01*
X394307Y-39800D01*
G01X421665Y-55550D02*
X422975Y-56133D01*
X424722Y-55550D01*
X425813Y-54384D01*
X426687Y-52925D01*
X427996Y-48259D01*
X430835Y-38634D01*
G01X423848D02*
X427996Y-48259D01*
G01X443750Y-50300D02*
X442440Y-50008D01*
X441130Y-48842D01*
X440256Y-46800D01*
X439820Y-44467D01*
X440256Y-42133D01*
X441130Y-40092D01*
X442440Y-38925D01*
X443750Y-38634D01*
X445060Y-38925D01*
X446370Y-40092D01*
X447243Y-42133D01*
X447462Y-44467D01*
X447243Y-46800D01*
X446370Y-48842D01*
X445060Y-50008D01*
X443750Y-50300D01*
G01X457538Y-38634D02*
Y-46800D01*
X458412Y-48842D01*
X459722Y-50008D01*
X461250Y-50300D01*
X462778Y-50008D01*
X464088Y-48842D01*
X464962Y-46800D01*
G01Y-50300D02*
Y-38634D01*
G01X475693Y-50300D02*
Y-38634D01*
G01Y-40967D02*
X476785Y-39800D01*
X477877Y-38925D01*
X479405Y-38634D01*
X480496Y-38925D01*
X481807Y-39800D01*
G01X510693Y-50300D02*
Y-38634D01*
G01Y-40967D02*
X511785Y-39800D01*
X512877Y-38925D01*
X514405Y-38634D01*
X515496Y-38925D01*
X516807Y-39800D01*
G01X527975Y-42425D02*
X534962D01*
X534307Y-40383D01*
X533215Y-39217D01*
X531687Y-38634D01*
X530158Y-38925D01*
X528848Y-39800D01*
X527975Y-41842D01*
X527538Y-43592D01*
Y-45342D01*
X527975Y-47092D01*
X529067Y-48842D01*
X530377Y-50008D01*
X531905Y-50300D01*
X533433Y-49717D01*
X534962Y-47967D01*
G01X547440Y-50300D02*
Y-35425D01*
X547877Y-33967D01*
X548750Y-33092D01*
X550060Y-32800D01*
X551370Y-33383D01*
X552025Y-34842D01*
G01X549405Y-39800D02*
X545038D01*
G01X562975Y-42425D02*
X569962D01*
X569307Y-40383D01*
X568215Y-39217D01*
X566687Y-38634D01*
X565158Y-38925D01*
X563848Y-39800D01*
X562975Y-41842D01*
X562538Y-43592D01*
Y-45342D01*
X562975Y-47092D01*
X564067Y-48842D01*
X565377Y-50008D01*
X566905Y-50300D01*
X568433Y-49717D01*
X569962Y-47967D01*
G01X580693Y-50300D02*
Y-38634D01*
G01Y-40967D02*
X581785Y-39800D01*
X582877Y-38925D01*
X584405Y-38634D01*
X585496Y-38925D01*
X586807Y-39800D01*
G01X597975Y-42425D02*
X604962D01*
X604307Y-40383D01*
X603215Y-39217D01*
X601687Y-38634D01*
X600158Y-38925D01*
X598848Y-39800D01*
X597975Y-41842D01*
X597538Y-43592D01*
Y-45342D01*
X597975Y-47092D01*
X599067Y-48842D01*
X600377Y-50008D01*
X601905Y-50300D01*
X603433Y-49717D01*
X604962Y-47967D01*
G01X615038Y-50300D02*
Y-38634D01*
G01Y-41550D02*
X615912Y-40092D01*
X617222Y-38925D01*
X618968Y-38634D01*
X620496Y-38925D01*
X621807Y-40092D01*
X622462Y-42133D01*
Y-50300D01*
G01X639743Y-40092D02*
X638215Y-38925D01*
X636905Y-38634D01*
X635158Y-39217D01*
X633848Y-40383D01*
X632975Y-42425D01*
X632756Y-44467D01*
X632975Y-46509D01*
X633848Y-48259D01*
X635158Y-49717D01*
X636905Y-50300D01*
X638433Y-49717D01*
X639743Y-48550D01*
G01X650475Y-42425D02*
X657462D01*
X656807Y-40383D01*
X655715Y-39217D01*
X654187Y-38634D01*
X652658Y-38925D01*
X651348Y-39800D01*
X650475Y-41842D01*
X650038Y-43592D01*
Y-45342D01*
X650475Y-47092D01*
X651567Y-48842D01*
X652877Y-50008D01*
X654405Y-50300D01*
X655933Y-49717D01*
X657462Y-47967D01*
G01X688750Y-32800D02*
Y-50300D01*
G01X685693Y-38634D02*
X691807D01*
G01X706250Y-50300D02*
X704940Y-50008D01*
X703630Y-48842D01*
X702756Y-46800D01*
X702320Y-44467D01*
X702756Y-42133D01*
X703630Y-40092D01*
X704940Y-38925D01*
X706250Y-38634D01*
X707560Y-38925D01*
X708870Y-40092D01*
X709743Y-42133D01*
X709962Y-44467D01*
X709743Y-46800D01*
X708870Y-48842D01*
X707560Y-50008D01*
X706250Y-50300D01*
G01X739940D02*
Y-35425D01*
X740377Y-33967D01*
X741250Y-33092D01*
X742560Y-32800D01*
X743870Y-33383D01*
X744525Y-34842D01*
G01X741905Y-39800D02*
X737538D01*
G01X758750Y-38634D02*
Y-50300D01*
G01Y-33967D02*
X758313Y-33675D01*
Y-33092D01*
X758750Y-32800D01*
X759187Y-33092D01*
Y-33675D01*
X758750Y-33967D01*
G01X772538Y-50300D02*
Y-38634D01*
G01Y-41550D02*
X773412Y-40092D01*
X774722Y-38925D01*
X776468Y-38634D01*
X777996Y-38925D01*
X779307Y-40092D01*
X779962Y-42133D01*
Y-50300D01*
G01X797680Y-32800D02*
Y-50300D01*
G01Y-47676D02*
X796807Y-49134D01*
X795496Y-50008D01*
X793968Y-50300D01*
X792222Y-49717D01*
X790912Y-48259D01*
X790038Y-46509D01*
X789820Y-44467D01*
X790038Y-42425D01*
X790912Y-40675D01*
X792222Y-39217D01*
X793968Y-38634D01*
X795496Y-38925D01*
X796588Y-39509D01*
X797680Y-40675D01*
G01X828750Y-32800D02*
Y-50300D01*
G01X825693Y-38634D02*
X831807D01*
G01X842538Y-50300D02*
Y-32800D01*
G01Y-41258D02*
X843630Y-39800D01*
X844722Y-38925D01*
X846468Y-38634D01*
X847778Y-38925D01*
X849307Y-40092D01*
X849962Y-41842D01*
Y-50300D01*
G01X860475Y-42425D02*
X867462D01*
X866807Y-40383D01*
X865715Y-39217D01*
X864187Y-38634D01*
X862658Y-38925D01*
X861348Y-39800D01*
X860475Y-41842D01*
X860038Y-43592D01*
Y-45342D01*
X860475Y-47092D01*
X861567Y-48842D01*
X862877Y-50008D01*
X864405Y-50300D01*
X865933Y-49717D01*
X867462Y-47967D01*
G01X893947Y-50300D02*
Y-32800D01*
X898313D01*
X900060Y-33675D01*
X901370Y-34842D01*
X902462Y-36591D01*
X903335Y-38634D01*
X903553Y-41550D01*
X903335Y-44467D01*
X902462Y-46509D01*
X901370Y-48259D01*
X900060Y-49425D01*
X898313Y-50300D01*
X893947D01*
G01X911883D02*
Y-32800D01*
X917123D01*
X918870Y-33675D01*
X920180Y-35717D01*
X920617Y-38050D01*
X920180Y-40383D01*
X919088Y-42133D01*
X917123Y-43009D01*
X911883D01*
G01X951250Y-38634D02*
Y-50300D01*
G01Y-33967D02*
X950813Y-33675D01*
Y-33092D01*
X951250Y-32800D01*
X951687Y-33092D01*
Y-33675D01*
X951250Y-33967D01*
G01X962200Y-50300D02*
Y-38634D01*
G01Y-41842D02*
X962855Y-40383D01*
X963947Y-39217D01*
X965475Y-38634D01*
X967003Y-39217D01*
X968095Y-40383D01*
X968750Y-41842D01*
Y-50300D01*
G01Y-41842D02*
X969405Y-40383D01*
X970496Y-39217D01*
X972025Y-38634D01*
X973553Y-39217D01*
X974645Y-40383D01*
X975300Y-42133D01*
Y-50300D01*
G01X982320Y-56133D02*
Y-38634D01*
G01Y-41258D02*
X983412Y-39800D01*
X984503Y-38925D01*
X986250Y-38634D01*
X987778Y-38925D01*
X989307Y-40383D01*
X989962Y-42425D01*
X990180Y-44467D01*
X989962Y-46509D01*
X989307Y-48550D01*
X987996Y-49717D01*
X986250Y-50300D01*
X984722Y-50008D01*
X983193Y-49134D01*
X982320Y-47967D01*
G01X1000475Y-42425D02*
X1007462D01*
X1006807Y-40383D01*
X1005715Y-39217D01*
X1004187Y-38634D01*
X1002658Y-38925D01*
X1001348Y-39800D01*
X1000475Y-41842D01*
X1000038Y-43592D01*
Y-45342D01*
X1000475Y-47092D01*
X1001567Y-48842D01*
X1002877Y-50008D01*
X1004405Y-50300D01*
X1005933Y-49717D01*
X1007462Y-47967D01*
G01X1025180Y-32800D02*
Y-50300D01*
G01Y-47676D02*
X1024307Y-49134D01*
X1022996Y-50008D01*
X1021468Y-50300D01*
X1019722Y-49717D01*
X1018412Y-48259D01*
X1017538Y-46509D01*
X1017320Y-44467D01*
X1017538Y-42425D01*
X1018412Y-40675D01*
X1019722Y-39217D01*
X1021468Y-38634D01*
X1022996Y-38925D01*
X1024088Y-39509D01*
X1025180Y-40675D01*
G01X1042680Y-50300D02*
Y-38634D01*
G01Y-40675D02*
X1041807Y-39509D01*
X1040496Y-38925D01*
X1038968Y-38634D01*
X1037440Y-39217D01*
X1036130Y-40383D01*
X1035256Y-42133D01*
X1034820Y-44467D01*
X1035256Y-46800D01*
X1036130Y-48550D01*
X1037440Y-49717D01*
X1038968Y-50300D01*
X1040496Y-50008D01*
X1041807Y-49134D01*
X1042680Y-47967D01*
G01X1052538Y-50300D02*
Y-38634D01*
G01Y-41550D02*
X1053412Y-40092D01*
X1054722Y-38925D01*
X1056468Y-38634D01*
X1057996Y-38925D01*
X1059307Y-40092D01*
X1059962Y-42133D01*
Y-50300D01*
G01X1077243Y-40092D02*
X1075715Y-38925D01*
X1074405Y-38634D01*
X1072658Y-39217D01*
X1071348Y-40383D01*
X1070475Y-42425D01*
X1070256Y-44467D01*
X1070475Y-46509D01*
X1071348Y-48259D01*
X1072658Y-49717D01*
X1074405Y-50300D01*
X1075933Y-49717D01*
X1077243Y-48550D01*
G01X1087975Y-42425D02*
X1094962D01*
X1094307Y-40383D01*
X1093215Y-39217D01*
X1091687Y-38634D01*
X1090158Y-38925D01*
X1088848Y-39800D01*
X1087975Y-41842D01*
X1087538Y-43592D01*
Y-45342D01*
X1087975Y-47092D01*
X1089067Y-48842D01*
X1090377Y-50008D01*
X1091905Y-50300D01*
X1093433Y-49717D01*
X1094962Y-47967D01*
G01X1126250Y-32800D02*
Y-50300D01*
G01X1123193Y-38634D02*
X1129307D01*
G01X1140693Y-50300D02*
Y-38634D01*
G01Y-40967D02*
X1141785Y-39800D01*
X1142877Y-38925D01*
X1144405Y-38634D01*
X1145496Y-38925D01*
X1146807Y-39800D01*
G01X1165180Y-50300D02*
Y-38634D01*
G01Y-40675D02*
X1164307Y-39509D01*
X1162996Y-38925D01*
X1161468Y-38634D01*
X1159940Y-39217D01*
X1158630Y-40383D01*
X1157756Y-42133D01*
X1157320Y-44467D01*
X1157756Y-46800D01*
X1158630Y-48550D01*
X1159940Y-49717D01*
X1161468Y-50300D01*
X1162996Y-50008D01*
X1164307Y-49134D01*
X1165180Y-47967D01*
G01X1182243Y-40092D02*
X1180715Y-38925D01*
X1179405Y-38634D01*
X1177658Y-39217D01*
X1176348Y-40383D01*
X1175475Y-42425D01*
X1175256Y-44467D01*
X1175475Y-46509D01*
X1176348Y-48259D01*
X1177658Y-49717D01*
X1179405Y-50300D01*
X1180933Y-49717D01*
X1182243Y-48550D01*
G01X1192975Y-42425D02*
X1199962D01*
X1199307Y-40383D01*
X1198215Y-39217D01*
X1196687Y-38634D01*
X1195158Y-38925D01*
X1193848Y-39800D01*
X1192975Y-41842D01*
X1192538Y-43592D01*
Y-45342D01*
X1192975Y-47092D01*
X1194067Y-48842D01*
X1195377Y-50008D01*
X1196905Y-50300D01*
X1198433Y-49717D01*
X1199962Y-47967D01*
G01X1210475Y-48259D02*
X1211567Y-49425D01*
X1213095Y-50300D01*
X1214405D01*
X1215715Y-49717D01*
X1216588Y-48842D01*
X1217025Y-47676D01*
X1216807Y-45925D01*
X1215933Y-45050D01*
X1212003Y-43300D01*
X1211130Y-41258D01*
X1211567Y-39800D01*
X1212440Y-38925D01*
X1213750Y-38634D01*
X1215060Y-38925D01*
X1216370Y-39800D01*
G01X1248750Y-38634D02*
Y-50300D01*
G01Y-33967D02*
X1248313Y-33675D01*
Y-33092D01*
X1248750Y-32800D01*
X1249187Y-33092D01*
Y-33675D01*
X1248750Y-33967D01*
G01X1262538Y-50300D02*
Y-38634D01*
G01Y-41550D02*
X1263412Y-40092D01*
X1264722Y-38925D01*
X1266468Y-38634D01*
X1267996Y-38925D01*
X1269307Y-40092D01*
X1269962Y-42133D01*
Y-50300D01*
G01X1301250D02*
Y-32800D01*
G01X1322680Y-50300D02*
Y-38634D01*
G01Y-40675D02*
X1321807Y-39509D01*
X1320496Y-38925D01*
X1318968Y-38634D01*
X1317440Y-39217D01*
X1316130Y-40383D01*
X1315256Y-42133D01*
X1314820Y-44467D01*
X1315256Y-46800D01*
X1316130Y-48550D01*
X1317440Y-49717D01*
X1318968Y-50300D01*
X1320496Y-50008D01*
X1321807Y-49134D01*
X1322680Y-47967D01*
G01X1331665Y-55550D02*
X1332975Y-56133D01*
X1334722Y-55550D01*
X1335813Y-54384D01*
X1336687Y-52925D01*
X1337996Y-48259D01*
X1340835Y-38634D01*
G01X1333848D02*
X1337996Y-48259D01*
G01X1350475Y-42425D02*
X1357462D01*
X1356807Y-40383D01*
X1355715Y-39217D01*
X1354187Y-38634D01*
X1352658Y-38925D01*
X1351348Y-39800D01*
X1350475Y-41842D01*
X1350038Y-43592D01*
Y-45342D01*
X1350475Y-47092D01*
X1351567Y-48842D01*
X1352877Y-50008D01*
X1354405Y-50300D01*
X1355933Y-49717D01*
X1357462Y-47967D01*
G01X1368193Y-50300D02*
Y-38634D01*
G01Y-40967D02*
X1369285Y-39800D01*
X1370377Y-38925D01*
X1371905Y-38634D01*
X1372996Y-38925D01*
X1374307Y-39800D01*
G01X1401883Y-32800D02*
Y-50300D01*
X1410617D01*
G01X1418947Y-46800D02*
X1420256Y-48842D01*
X1422003Y-50008D01*
X1423968Y-50300D01*
X1425715Y-50008D01*
X1427462Y-48550D01*
X1428553Y-46800D01*
X1428772Y-45050D01*
X1428335Y-43009D01*
X1426807Y-41550D01*
X1425278Y-40967D01*
X1423313D01*
G01X1425278D02*
X1426588Y-40092D01*
X1427680Y-38634D01*
X1428117Y-36884D01*
X1427680Y-35133D01*
X1426588Y-33675D01*
X1424623Y-32800D01*
X1422658Y-33092D01*
X1420693Y-34259D01*
G01X1441250Y-50883D02*
X1440813Y-50592D01*
Y-50008D01*
X1441250Y-49717D01*
X1441687Y-50008D01*
Y-50592D01*
X1441250Y-50883D01*
G01X999127Y722030D02*
X1004367D01*
G01X1001747D02*
Y704530D01*
G01X999127D02*
X1004367D01*
G01X1013570D02*
Y722030D01*
X1019247Y707447D01*
X1024924Y722030D01*
Y704530D01*
G01X1032380D02*
Y722030D01*
X1037620D01*
X1039367Y721155D01*
X1040677Y719113D01*
X1041114Y716780D01*
X1040677Y714447D01*
X1039585Y712697D01*
X1037620Y711821D01*
X1032380D01*
G01X1053155Y698697D02*
X1050972Y701613D01*
X1049880Y704530D01*
Y716196D01*
X1050972Y719113D01*
X1053155Y722030D01*
G01X1071747Y704530D02*
X1070000Y704822D01*
X1068472Y705988D01*
X1067162Y707738D01*
X1066288Y709780D01*
X1065852Y712113D01*
Y714447D01*
X1066288Y716780D01*
X1067162Y718822D01*
X1068472Y720571D01*
X1070000Y721738D01*
X1071747Y722030D01*
X1073493Y721738D01*
X1075022Y720571D01*
X1076332Y718822D01*
X1077206Y716780D01*
X1077642Y714447D01*
Y712113D01*
X1077206Y709780D01*
X1076332Y707738D01*
X1075022Y705988D01*
X1073493Y704822D01*
X1071747Y704530D01*
G01X1085535D02*
Y722030D01*
G01Y713572D02*
X1086627Y715030D01*
X1087719Y715905D01*
X1089465Y716196D01*
X1090775Y715905D01*
X1092304Y714738D01*
X1092959Y712988D01*
Y704530D01*
G01X1100197D02*
Y716196D01*
G01Y712988D02*
X1100852Y714447D01*
X1101944Y715613D01*
X1103472Y716196D01*
X1105000Y715613D01*
X1106092Y714447D01*
X1106747Y712988D01*
Y704530D01*
G01Y712988D02*
X1107402Y714447D01*
X1108493Y715613D01*
X1110022Y716196D01*
X1111550Y715613D01*
X1112642Y714447D01*
X1113297Y712697D01*
Y704530D01*
G01X1125339Y698697D02*
X1127522Y701613D01*
X1128614Y704530D01*
Y716196D01*
X1127522Y719113D01*
X1125339Y722030D01*
G01X977244Y739180D02*
Y756680D01*
X981610D01*
X983357Y755805D01*
X984667Y754638D01*
X985759Y752889D01*
X986632Y750846D01*
X986850Y747930D01*
X986632Y745013D01*
X985759Y742971D01*
X984667Y741221D01*
X983357Y740055D01*
X981610Y739180D01*
X977244D01*
G01X995180D02*
Y756680D01*
X1000420D01*
X1002167Y755805D01*
X1003477Y753763D01*
X1003914Y751430D01*
X1003477Y749097D01*
X1002385Y747347D01*
X1000420Y746471D01*
X995180D01*
G01X1031927Y756680D02*
X1037167D01*
G01X1034547D02*
Y739180D01*
G01X1031927D02*
X1037167D01*
G01X1046370D02*
Y756680D01*
X1052047Y742097D01*
X1057724Y756680D01*
Y739180D01*
G01X1065180D02*
Y756680D01*
X1070420D01*
X1072167Y755805D01*
X1073477Y753763D01*
X1073914Y751430D01*
X1073477Y749097D01*
X1072385Y747347D01*
X1070420Y746471D01*
X1065180D01*
G01X1091414Y739180D02*
X1082680D01*
Y756680D01*
X1091414D01*
G01X1087920Y748222D02*
X1082680D01*
G01X1099744Y739180D02*
Y756680D01*
X1104110D01*
X1105857Y755805D01*
X1107167Y754638D01*
X1108259Y752889D01*
X1109132Y750846D01*
X1109350Y747930D01*
X1109132Y745013D01*
X1108259Y742971D01*
X1107167Y741221D01*
X1105857Y740055D01*
X1104110Y739180D01*
X1099744D01*
G01X1116588D02*
X1122047Y756680D01*
X1127506Y739180D01*
G01X1125540Y745305D02*
X1118553D01*
G01X1134525Y739180D02*
Y756680D01*
X1144569Y739180D01*
Y756680D01*
G01X1161850Y755221D02*
X1160540Y756097D01*
X1159012Y756680D01*
X1157265D01*
X1155300Y755805D01*
X1153772Y754347D01*
X1152680Y752596D01*
X1151807Y749680D01*
X1151588Y747055D01*
X1152025Y744430D01*
X1152680Y742680D01*
X1153990Y740930D01*
X1155519Y739763D01*
X1157047Y739180D01*
X1158575D01*
X1160104Y739763D01*
X1161414Y740638D01*
X1162506Y741804D01*
G01X1178914Y739180D02*
X1170180D01*
Y756680D01*
X1178914D01*
G01X1175420Y748222D02*
X1170180D01*
G01X1209547Y756680D02*
Y739180D01*
G01X1204525Y756680D02*
X1214569D01*
G01X1221588Y739180D02*
X1227047Y756680D01*
X1232506Y739180D01*
G01X1230540Y745305D02*
X1223553D01*
G01X1246293Y748513D02*
X1247167Y749388D01*
X1247822Y750846D01*
X1248259Y752889D01*
X1247822Y754638D01*
X1246949Y755805D01*
X1245420Y756680D01*
X1239525D01*
Y739180D01*
X1246730D01*
X1248259Y740346D01*
X1249132Y742097D01*
X1249569Y744138D01*
X1249132Y746180D01*
X1247822Y747930D01*
X1246293Y748513D01*
X1239525D01*
G01X1257680Y756680D02*
Y739180D01*
X1266414D01*
G01X1283914D02*
X1275180D01*
Y756680D01*
X1283914D01*
G01X1280420Y748222D02*
X1275180D01*
G01X1297047Y738597D02*
X1296610Y738888D01*
Y739472D01*
X1297047Y739763D01*
X1297484Y739472D01*
Y738888D01*
X1297047Y738597D01*
G01Y746471D02*
X1296610Y746763D01*
Y747347D01*
X1297047Y747638D01*
X1297484Y747347D01*
Y746763D01*
X1297047Y746471D01*
G01X1327680Y756680D02*
Y739180D01*
X1336414D01*
G01X1344744Y742680D02*
X1346053Y740638D01*
X1347800Y739472D01*
X1349765Y739180D01*
X1351512Y739472D01*
X1353259Y740930D01*
X1354350Y742680D01*
X1354569Y744430D01*
X1354132Y746471D01*
X1352604Y747930D01*
X1351075Y748513D01*
X1349110D01*
G01X1351075D02*
X1352385Y749388D01*
X1353477Y750846D01*
X1353914Y752596D01*
X1353477Y754347D01*
X1352385Y755805D01*
X1350420Y756680D01*
X1348455Y756388D01*
X1346490Y755221D01*
G01X1027997Y635230D02*
Y652730D01*
X1025377Y649230D01*
G01Y635230D02*
X1030617D01*
G01X1045497Y652730D02*
X1043750Y652147D01*
X1042440Y650688D01*
X1041567Y648939D01*
X1040912Y646605D01*
X1040694Y643980D01*
X1040912Y641355D01*
X1041567Y639021D01*
X1042440Y637271D01*
X1043750Y635813D01*
X1045497Y635230D01*
X1047243Y635813D01*
X1048554Y637271D01*
X1049427Y639021D01*
X1050082Y641355D01*
X1050300Y643980D01*
X1050082Y646605D01*
X1049427Y648939D01*
X1048554Y650688D01*
X1047243Y652147D01*
X1045497Y652730D01*
G01X1062997D02*
X1061250Y652147D01*
X1059940Y650688D01*
X1059067Y648939D01*
X1058412Y646605D01*
X1058194Y643980D01*
X1058412Y641355D01*
X1059067Y639021D01*
X1059940Y637271D01*
X1061250Y635813D01*
X1062997Y635230D01*
X1064743Y635813D01*
X1066054Y637271D01*
X1066927Y639021D01*
X1067582Y641355D01*
X1067800Y643980D01*
X1067582Y646605D01*
X1066927Y648939D01*
X1066054Y650688D01*
X1064743Y652147D01*
X1062997Y652730D01*
G01X1080497Y634647D02*
X1080060Y634938D01*
Y635522D01*
X1080497Y635813D01*
X1080934Y635522D01*
Y634938D01*
X1080497Y634647D01*
G01X1097997Y652730D02*
X1096250Y652147D01*
X1094940Y650688D01*
X1094067Y648939D01*
X1093412Y646605D01*
X1093194Y643980D01*
X1093412Y641355D01*
X1094067Y639021D01*
X1094940Y637271D01*
X1096250Y635813D01*
X1097997Y635230D01*
X1099743Y635813D01*
X1101054Y637271D01*
X1101927Y639021D01*
X1102582Y641355D01*
X1102800Y643980D01*
X1102582Y646605D01*
X1101927Y648939D01*
X1101054Y650688D01*
X1099743Y652147D01*
X1097997Y652730D01*
G01X1036747Y669880D02*
X1038275Y670172D01*
X1040022Y671046D01*
X1041114Y672504D01*
X1041550Y674547D01*
X1041114Y676588D01*
X1039804Y678338D01*
X1037839Y679213D01*
X1035655D01*
X1034345Y679797D01*
X1033253Y681255D01*
X1032817Y683296D01*
X1033472Y685338D01*
X1035000Y686797D01*
X1036747Y687380D01*
X1038493Y686797D01*
X1040022Y685338D01*
X1040677Y683296D01*
X1040240Y681255D01*
X1039149Y679797D01*
X1037839Y679213D01*
X1035655D01*
X1033690Y678338D01*
X1032380Y676588D01*
X1031944Y674547D01*
X1032380Y672504D01*
X1033472Y671046D01*
X1035219Y670172D01*
X1036747Y669880D01*
G01X1049444Y672504D02*
X1050753Y671046D01*
X1052282Y670172D01*
X1054247Y669880D01*
X1056212Y670463D01*
X1057740Y671630D01*
X1058832Y673671D01*
X1059050Y676005D01*
X1058614Y678338D01*
X1057522Y679797D01*
X1055993Y680963D01*
X1054465Y681255D01*
X1052937Y680963D01*
X1050972Y679797D01*
X1051627Y687380D01*
X1057522D01*
G01X1071747Y669297D02*
X1071310Y669588D01*
Y670172D01*
X1071747Y670463D01*
X1072184Y670172D01*
Y669588D01*
X1071747Y669297D01*
G01X1089247Y687380D02*
X1087500Y686797D01*
X1086190Y685338D01*
X1085317Y683589D01*
X1084662Y681255D01*
X1084444Y678630D01*
X1084662Y676005D01*
X1085317Y673671D01*
X1086190Y671921D01*
X1087500Y670463D01*
X1089247Y669880D01*
X1090993Y670463D01*
X1092304Y671921D01*
X1093177Y673671D01*
X1093832Y676005D01*
X1094050Y678630D01*
X1093832Y681255D01*
X1093177Y683589D01*
X1092304Y685338D01*
X1090993Y686797D01*
X1089247Y687380D01*
G01X1249367Y635230D02*
Y652730D01*
X1241288Y640188D01*
X1252206D01*
G01X1264247Y634647D02*
X1263810Y634938D01*
Y635522D01*
X1264247Y635813D01*
X1264684Y635522D01*
Y634938D01*
X1264247Y634647D01*
G01X1281747Y652730D02*
X1280000Y652147D01*
X1278690Y650688D01*
X1277817Y648939D01*
X1277162Y646605D01*
X1276944Y643980D01*
X1277162Y641355D01*
X1277817Y639021D01*
X1278690Y637271D01*
X1280000Y635813D01*
X1281747Y635230D01*
X1283493Y635813D01*
X1284804Y637271D01*
X1285677Y639021D01*
X1286332Y641355D01*
X1286550Y643980D01*
X1286332Y646605D01*
X1285677Y648939D01*
X1284804Y650688D01*
X1283493Y652147D01*
X1281747Y652730D01*
G01X1295317Y634647D02*
X1303177Y652730D01*
G01X1316747Y635230D02*
X1318275Y635522D01*
X1320022Y636396D01*
X1321114Y637854D01*
X1321550Y639897D01*
X1321114Y641938D01*
X1319804Y643688D01*
X1317839Y644563D01*
X1315655D01*
X1314345Y645147D01*
X1313253Y646605D01*
X1312817Y648646D01*
X1313472Y650688D01*
X1315000Y652147D01*
X1316747Y652730D01*
X1318493Y652147D01*
X1320022Y650688D01*
X1320677Y648646D01*
X1320240Y646605D01*
X1319149Y645147D01*
X1317839Y644563D01*
X1315655D01*
X1313690Y643688D01*
X1312380Y641938D01*
X1311944Y639897D01*
X1312380Y637854D01*
X1313472Y636396D01*
X1315219Y635522D01*
X1316747Y635230D01*
G01X1334247Y634647D02*
X1333810Y634938D01*
Y635522D01*
X1334247Y635813D01*
X1334684Y635522D01*
Y634938D01*
X1334247Y634647D01*
G01X1351747Y652730D02*
X1350000Y652147D01*
X1348690Y650688D01*
X1347817Y648939D01*
X1347162Y646605D01*
X1346944Y643980D01*
X1347162Y641355D01*
X1347817Y639021D01*
X1348690Y637271D01*
X1350000Y635813D01*
X1351747Y635230D01*
X1353493Y635813D01*
X1354804Y637271D01*
X1355677Y639021D01*
X1356332Y641355D01*
X1356550Y643980D01*
X1356332Y646605D01*
X1355677Y648939D01*
X1354804Y650688D01*
X1353493Y652147D01*
X1351747Y652730D01*
G01X1205197Y722030D02*
X1208253Y704530D01*
X1211747Y722030D01*
X1215240Y704530D01*
X1218297Y722030D01*
G01X1226627D02*
X1231867D01*
G01X1229247D02*
Y704530D01*
G01X1226627D02*
X1231867D01*
G01X1241944D02*
Y722030D01*
X1246310D01*
X1248057Y721155D01*
X1249367Y719988D01*
X1250459Y718239D01*
X1251332Y716196D01*
X1251550Y713280D01*
X1251332Y710363D01*
X1250459Y708321D01*
X1249367Y706571D01*
X1248057Y705405D01*
X1246310Y704530D01*
X1241944D01*
G01X1264247Y722030D02*
Y704530D01*
G01X1259225Y722030D02*
X1269269D01*
G01X1277162Y704530D02*
Y722030D01*
G01X1286332D02*
Y704530D01*
G01Y713280D02*
X1277162D01*
G01X1298155Y698697D02*
X1295972Y701613D01*
X1294880Y704530D01*
Y716196D01*
X1295972Y719113D01*
X1298155Y722030D01*
G01X1310197Y704530D02*
Y716196D01*
G01Y712988D02*
X1310852Y714447D01*
X1311944Y715613D01*
X1313472Y716196D01*
X1315000Y715613D01*
X1316092Y714447D01*
X1316747Y712988D01*
Y704530D01*
G01Y712988D02*
X1317402Y714447D01*
X1318493Y715613D01*
X1320022Y716196D01*
X1321550Y715613D01*
X1322642Y714447D01*
X1323297Y712697D01*
Y704530D01*
G01X1334247Y716196D02*
Y704530D01*
G01Y720863D02*
X1333810Y721155D01*
Y721738D01*
X1334247Y722030D01*
X1334684Y721738D01*
Y721155D01*
X1334247Y720863D01*
G01X1351747Y704530D02*
Y722030D01*
G01X1365972Y706571D02*
X1367064Y705405D01*
X1368592Y704530D01*
X1369902D01*
X1371212Y705113D01*
X1372085Y705988D01*
X1372522Y707154D01*
X1372304Y708905D01*
X1371430Y709780D01*
X1367500Y711530D01*
X1366627Y713572D01*
X1367064Y715030D01*
X1367937Y715905D01*
X1369247Y716196D01*
X1370557Y715905D01*
X1371867Y715030D01*
G01X1387839Y698697D02*
X1390022Y701613D01*
X1391114Y704530D01*
Y716196D01*
X1390022Y719113D01*
X1387839Y722030D01*
G01X1241944Y672504D02*
X1243253Y671046D01*
X1244782Y670172D01*
X1246747Y669880D01*
X1248712Y670463D01*
X1250240Y671630D01*
X1251332Y673671D01*
X1251550Y676005D01*
X1251114Y678338D01*
X1250022Y679797D01*
X1248493Y680963D01*
X1246965Y681255D01*
X1245437Y680963D01*
X1243472Y679797D01*
X1244127Y687380D01*
X1250022D01*
G01X1264247Y669297D02*
X1263810Y669588D01*
Y670172D01*
X1264247Y670463D01*
X1264684Y670172D01*
Y669588D01*
X1264247Y669297D01*
G01X1276944Y672504D02*
X1278253Y671046D01*
X1279782Y670172D01*
X1281747Y669880D01*
X1283712Y670463D01*
X1285240Y671630D01*
X1286332Y673671D01*
X1286550Y676005D01*
X1286114Y678338D01*
X1285022Y679797D01*
X1283493Y680963D01*
X1281965Y681255D01*
X1280437Y680963D01*
X1278472Y679797D01*
X1279127Y687380D01*
X1285022D01*
G01X1295317Y669297D02*
X1303177Y687380D01*
G01X1316310Y669880D02*
X1316747Y673671D01*
X1317402Y676880D01*
X1318275Y679797D01*
X1319367Y683005D01*
X1321114Y687380D01*
X1312380D01*
G01X1334247Y669297D02*
X1333810Y669588D01*
Y670172D01*
X1334247Y670463D01*
X1334684Y670172D01*
Y669588D01*
X1334247Y669297D01*
G01X1346944Y672504D02*
X1348253Y671046D01*
X1349782Y670172D01*
X1351747Y669880D01*
X1353712Y670463D01*
X1355240Y671630D01*
X1356332Y673671D01*
X1356550Y676005D01*
X1356114Y678338D01*
X1355022Y679797D01*
X1353493Y680963D01*
X1351965Y681255D01*
X1350437Y680963D01*
X1348472Y679797D01*
X1349127Y687380D01*
X1355022D01*
G01X1486944Y635230D02*
Y652730D01*
X1491310D01*
X1493057Y651855D01*
X1494367Y650688D01*
X1495459Y648939D01*
X1496332Y646896D01*
X1496550Y643980D01*
X1496332Y641063D01*
X1495459Y639021D01*
X1494367Y637271D01*
X1493057Y636105D01*
X1491310Y635230D01*
X1486944D01*
G01X1504880D02*
Y652730D01*
X1510120D01*
X1511867Y651855D01*
X1513177Y649813D01*
X1513614Y647480D01*
X1513177Y645147D01*
X1512085Y643397D01*
X1510120Y642521D01*
X1504880D01*
G01X1474247Y722030D02*
Y704530D01*
G01X1469225Y722030D02*
X1479269D01*
G01X1491747Y704530D02*
Y712405D01*
X1487380Y722030D01*
G01X1496114D02*
X1491747Y712405D01*
G01X1504880Y704530D02*
Y722030D01*
X1510120D01*
X1511867Y721155D01*
X1513177Y719113D01*
X1513614Y716780D01*
X1513177Y714447D01*
X1512085Y712697D01*
X1510120Y711821D01*
X1504880D01*
G01X1531114Y704530D02*
X1522380D01*
Y722030D01*
X1531114D01*
G01X1527620Y713572D02*
X1522380D01*
G01X1486944Y669880D02*
Y687380D01*
X1491310D01*
X1493057Y686505D01*
X1494367Y685338D01*
X1495459Y683589D01*
X1496332Y681546D01*
X1496550Y678630D01*
X1496332Y675713D01*
X1495459Y673671D01*
X1494367Y671921D01*
X1493057Y670755D01*
X1491310Y669880D01*
X1486944D01*
G01X1504880D02*
Y687380D01*
X1510120D01*
X1511867Y686505D01*
X1513177Y684463D01*
X1513614Y682130D01*
X1513177Y679797D01*
X1512085Y678047D01*
X1510120Y677171D01*
X1504880D01*
G01X1574880Y704530D02*
Y722030D01*
X1580339D01*
X1582085Y721155D01*
X1583177Y719988D01*
X1583614Y717655D01*
X1583177Y715321D01*
X1581867Y713863D01*
X1580339Y712988D01*
X1574880D01*
G01X1580339D02*
X1583614Y704530D01*
G01X1593472Y712405D02*
X1600459D01*
X1599804Y714447D01*
X1598712Y715613D01*
X1597184Y716196D01*
X1595655Y715905D01*
X1594345Y715030D01*
X1593472Y712988D01*
X1593035Y711238D01*
Y709488D01*
X1593472Y707738D01*
X1594564Y705988D01*
X1595874Y704822D01*
X1597402Y704530D01*
X1598930Y705113D01*
X1600459Y706863D01*
G01X1612937Y704530D02*
Y719405D01*
X1613374Y720863D01*
X1614247Y721738D01*
X1615557Y722030D01*
X1616867Y721447D01*
X1617522Y719988D01*
G01X1614902Y715030D02*
X1610535D01*
G01X1631747Y703947D02*
X1631310Y704238D01*
Y704822D01*
X1631747Y705113D01*
X1632184Y704822D01*
Y704238D01*
X1631747Y703947D01*
G01X1662380Y704530D02*
Y722030D01*
X1667620D01*
X1669367Y721155D01*
X1670677Y719113D01*
X1671114Y716780D01*
X1670677Y714447D01*
X1669585Y712697D01*
X1667620Y711821D01*
X1662380D01*
G01X1684247Y704530D02*
Y722030D01*
G01X1705677Y704530D02*
Y716196D01*
G01Y714155D02*
X1704804Y715321D01*
X1703493Y715905D01*
X1701965Y716196D01*
X1700437Y715613D01*
X1699127Y714447D01*
X1698253Y712697D01*
X1697817Y710363D01*
X1698253Y708030D01*
X1699127Y706280D01*
X1700437Y705113D01*
X1701965Y704530D01*
X1703493Y704822D01*
X1704804Y705696D01*
X1705677Y706863D01*
G01X1715535Y704530D02*
Y716196D01*
G01Y713280D02*
X1716409Y714738D01*
X1717719Y715905D01*
X1719465Y716196D01*
X1720993Y715905D01*
X1722304Y714738D01*
X1722959Y712697D01*
Y704530D01*
G01X1733472Y712405D02*
X1740459D01*
X1739804Y714447D01*
X1738712Y715613D01*
X1737184Y716196D01*
X1735655Y715905D01*
X1734345Y715030D01*
X1733472Y712988D01*
X1733035Y711238D01*
Y709488D01*
X1733472Y707738D01*
X1734564Y705988D01*
X1735874Y704822D01*
X1737402Y704530D01*
X1738930Y705113D01*
X1740459Y706863D01*
G01X1618630Y652730D02*
Y635230D01*
X1627364D01*
G01X1636349Y649813D02*
X1637659Y651563D01*
X1639187Y652438D01*
X1640934Y652730D01*
X1643117Y652147D01*
X1644645Y650688D01*
X1645082Y648939D01*
X1644864Y647188D01*
X1643990Y645730D01*
X1639624Y642813D01*
X1637659Y640772D01*
X1636349Y637854D01*
X1635912Y635230D01*
X1645082D01*
G01X1654067Y634647D02*
X1661927Y652730D01*
G01X1671130D02*
Y635230D01*
X1679864D01*
G01X1695617D02*
Y652730D01*
X1687538Y640188D01*
X1698456D01*
G01X1618630Y687380D02*
Y669880D01*
X1627364D01*
G01X1636349Y684463D02*
X1637659Y686213D01*
X1639187Y687088D01*
X1640934Y687380D01*
X1643117Y686797D01*
X1644645Y685338D01*
X1645082Y683589D01*
X1644864Y681838D01*
X1643990Y680380D01*
X1639624Y677463D01*
X1637659Y675422D01*
X1636349Y672504D01*
X1635912Y669880D01*
X1645082D01*
G01X1654067Y669297D02*
X1661927Y687380D01*
G01X1671130D02*
Y669880D01*
X1679864D01*
G01X1695617D02*
Y687380D01*
X1687538Y674838D01*
X1698456D01*
G01X1779744Y703947D02*
X1789350Y716780D01*
G01X1784547Y719113D02*
Y701613D01*
G01X1789350Y703947D02*
X1779744Y716780D01*
G01X1777997Y710363D02*
X1791097D01*
G01X1816709D02*
X1822385D01*
G01X1849744Y704530D02*
Y722030D01*
X1854110D01*
X1855857Y721155D01*
X1857167Y719988D01*
X1858259Y718239D01*
X1859132Y716196D01*
X1859350Y713280D01*
X1859132Y710363D01*
X1858259Y708321D01*
X1857167Y706571D01*
X1855857Y705405D01*
X1854110Y704530D01*
X1849744D01*
G01X1868772Y712405D02*
X1875759D01*
X1875104Y714447D01*
X1874012Y715613D01*
X1872484Y716196D01*
X1870955Y715905D01*
X1869645Y715030D01*
X1868772Y712988D01*
X1868335Y711238D01*
Y709488D01*
X1868772Y707738D01*
X1869864Y705988D01*
X1871174Y704822D01*
X1872702Y704530D01*
X1874230Y705113D01*
X1875759Y706863D01*
G01X1885835Y704530D02*
Y716196D01*
G01Y713280D02*
X1886709Y714738D01*
X1888019Y715905D01*
X1889765Y716196D01*
X1891293Y715905D01*
X1892604Y714738D01*
X1893259Y712697D01*
Y704530D01*
G01X1907047D02*
X1905737Y704822D01*
X1904427Y705988D01*
X1903553Y708030D01*
X1903117Y710363D01*
X1903553Y712697D01*
X1904427Y714738D01*
X1905737Y715905D01*
X1907047Y716196D01*
X1908357Y715905D01*
X1909667Y714738D01*
X1910540Y712697D01*
X1910759Y710363D01*
X1910540Y708030D01*
X1909667Y705988D01*
X1908357Y704822D01*
X1907047Y704530D01*
G01X1924547Y722030D02*
Y704530D01*
G01X1921490Y716196D02*
X1927604D01*
G01X1938772Y712405D02*
X1945759D01*
X1945104Y714447D01*
X1944012Y715613D01*
X1942484Y716196D01*
X1940955Y715905D01*
X1939645Y715030D01*
X1938772Y712988D01*
X1938335Y711238D01*
Y709488D01*
X1938772Y707738D01*
X1939864Y705988D01*
X1941174Y704822D01*
X1942702Y704530D01*
X1944230Y705113D01*
X1945759Y706863D01*
G01X1956272Y706571D02*
X1957364Y705405D01*
X1958892Y704530D01*
X1960202D01*
X1961512Y705113D01*
X1962385Y705988D01*
X1962822Y707154D01*
X1962604Y708905D01*
X1961730Y709780D01*
X1957800Y711530D01*
X1956927Y713572D01*
X1957364Y715030D01*
X1958237Y715905D01*
X1959547Y716196D01*
X1960857Y715905D01*
X1962167Y715030D01*
G01X1994547Y722030D02*
Y704530D01*
G01X1991490Y716196D02*
X1997604D01*
G01X2008335Y704530D02*
Y722030D01*
G01Y713572D02*
X2009427Y715030D01*
X2010519Y715905D01*
X2012265Y716196D01*
X2013575Y715905D01*
X2015104Y714738D01*
X2015759Y712988D01*
Y704530D01*
G01X2033477D02*
Y716196D01*
G01Y714155D02*
X2032604Y715321D01*
X2031293Y715905D01*
X2029765Y716196D01*
X2028237Y715613D01*
X2026927Y714447D01*
X2026053Y712697D01*
X2025617Y710363D01*
X2026053Y708030D01*
X2026927Y706280D01*
X2028237Y705113D01*
X2029765Y704530D01*
X2031293Y704822D01*
X2032604Y705696D01*
X2033477Y706863D01*
G01X2047047Y722030D02*
Y704530D01*
G01X2043990Y716196D02*
X2050104D01*
G01X2082047Y722030D02*
Y704530D01*
G01X2078990Y716196D02*
X2085104D01*
G01X2095835Y704530D02*
Y722030D01*
G01Y713572D02*
X2096927Y715030D01*
X2098019Y715905D01*
X2099765Y716196D01*
X2101075Y715905D01*
X2102604Y714738D01*
X2103259Y712988D01*
Y704530D01*
G01X2117047Y716196D02*
Y704530D01*
G01Y720863D02*
X2116610Y721155D01*
Y721738D01*
X2117047Y722030D01*
X2117484Y721738D01*
Y721155D01*
X2117047Y720863D01*
G01X2131272Y706571D02*
X2132364Y705405D01*
X2133892Y704530D01*
X2135202D01*
X2136512Y705113D01*
X2137385Y705988D01*
X2137822Y707154D01*
X2137604Y708905D01*
X2136730Y709780D01*
X2132800Y711530D01*
X2131927Y713572D01*
X2132364Y715030D01*
X2133237Y715905D01*
X2134547Y716196D01*
X2135857Y715905D01*
X2137167Y715030D01*
G01X2166927Y722030D02*
X2172167D01*
G01X2169547D02*
Y704530D01*
G01X2166927D02*
X2172167D01*
G01X2180497D02*
Y716196D01*
G01Y712988D02*
X2181152Y714447D01*
X2182244Y715613D01*
X2183772Y716196D01*
X2185300Y715613D01*
X2186392Y714447D01*
X2187047Y712988D01*
Y704530D01*
G01Y712988D02*
X2187702Y714447D01*
X2188793Y715613D01*
X2190322Y716196D01*
X2191850Y715613D01*
X2192942Y714447D01*
X2193597Y712697D01*
Y704530D01*
G01X2200617Y698697D02*
Y716196D01*
G01Y713572D02*
X2201709Y715030D01*
X2202800Y715905D01*
X2204547Y716196D01*
X2206075Y715905D01*
X2207604Y714447D01*
X2208259Y712405D01*
X2208477Y710363D01*
X2208259Y708321D01*
X2207604Y706280D01*
X2206293Y705113D01*
X2204547Y704530D01*
X2203019Y704822D01*
X2201490Y705696D01*
X2200617Y706863D01*
G01X2218772Y712405D02*
X2225759D01*
X2225104Y714447D01*
X2224012Y715613D01*
X2222484Y716196D01*
X2220955Y715905D01*
X2219645Y715030D01*
X2218772Y712988D01*
X2218335Y711238D01*
Y709488D01*
X2218772Y707738D01*
X2219864Y705988D01*
X2221174Y704822D01*
X2222702Y704530D01*
X2224230Y705113D01*
X2225759Y706863D01*
G01X2243477Y722030D02*
Y704530D01*
G01Y707154D02*
X2242604Y705696D01*
X2241293Y704822D01*
X2239765Y704530D01*
X2238019Y705113D01*
X2236709Y706571D01*
X2235835Y708321D01*
X2235617Y710363D01*
X2235835Y712405D01*
X2236709Y714155D01*
X2238019Y715613D01*
X2239765Y716196D01*
X2241293Y715905D01*
X2242385Y715321D01*
X2243477Y714155D01*
G01X2260977Y704530D02*
Y716196D01*
G01Y714155D02*
X2260104Y715321D01*
X2258793Y715905D01*
X2257265Y716196D01*
X2255737Y715613D01*
X2254427Y714447D01*
X2253553Y712697D01*
X2253117Y710363D01*
X2253553Y708030D01*
X2254427Y706280D01*
X2255737Y705113D01*
X2257265Y704530D01*
X2258793Y704822D01*
X2260104Y705696D01*
X2260977Y706863D01*
G01X2270835Y704530D02*
Y716196D01*
G01Y713280D02*
X2271709Y714738D01*
X2273019Y715905D01*
X2274765Y716196D01*
X2276293Y715905D01*
X2277604Y714738D01*
X2278259Y712697D01*
Y704530D01*
G01X2295540Y714738D02*
X2294012Y715905D01*
X2292702Y716196D01*
X2290955Y715613D01*
X2289645Y714447D01*
X2288772Y712405D01*
X2288553Y710363D01*
X2288772Y708321D01*
X2289645Y706571D01*
X2290955Y705113D01*
X2292702Y704530D01*
X2294230Y705113D01*
X2295540Y706280D01*
G01X2306272Y712405D02*
X2313259D01*
X2312604Y714447D01*
X2311512Y715613D01*
X2309984Y716196D01*
X2308455Y715905D01*
X2307145Y715030D01*
X2306272Y712988D01*
X2305835Y711238D01*
Y709488D01*
X2306272Y707738D01*
X2307364Y705988D01*
X2308674Y704822D01*
X2310202Y704530D01*
X2311730Y705113D01*
X2313259Y706863D01*
G01X1854547Y681546D02*
Y669880D01*
G01Y686213D02*
X1854110Y686505D01*
Y687088D01*
X1854547Y687380D01*
X1854984Y687088D01*
Y686505D01*
X1854547Y686213D01*
G01X1868772Y671921D02*
X1869864Y670755D01*
X1871392Y669880D01*
X1872702D01*
X1874012Y670463D01*
X1874885Y671338D01*
X1875322Y672504D01*
X1875104Y674255D01*
X1874230Y675130D01*
X1870300Y676880D01*
X1869427Y678922D01*
X1869864Y680380D01*
X1870737Y681255D01*
X1872047Y681546D01*
X1873357Y681255D01*
X1874667Y680380D01*
G01X1902025Y669880D02*
Y687380D01*
X1912069Y669880D01*
Y687380D01*
G01X1924547Y669880D02*
X1922800Y670172D01*
X1921272Y671338D01*
X1919962Y673088D01*
X1919088Y675130D01*
X1918652Y677463D01*
Y679797D01*
X1919088Y682130D01*
X1919962Y684172D01*
X1921272Y685921D01*
X1922800Y687088D01*
X1924547Y687380D01*
X1926293Y687088D01*
X1927822Y685921D01*
X1929132Y684172D01*
X1930006Y682130D01*
X1930442Y679797D01*
Y677463D01*
X1930006Y675130D01*
X1929132Y673088D01*
X1927822Y671338D01*
X1926293Y670172D01*
X1924547Y669880D01*
G01X1942047Y687380D02*
Y669880D01*
G01X1937025Y687380D02*
X1947069D01*
G01X1973335Y681546D02*
Y673380D01*
X1974209Y671338D01*
X1975519Y670172D01*
X1977047Y669880D01*
X1978575Y670172D01*
X1979885Y671338D01*
X1980759Y673380D01*
G01Y669880D02*
Y681546D01*
G01X1991272Y671921D02*
X1992364Y670755D01*
X1993892Y669880D01*
X1995202D01*
X1996512Y670463D01*
X1997385Y671338D01*
X1997822Y672504D01*
X1997604Y674255D01*
X1996730Y675130D01*
X1992800Y676880D01*
X1991927Y678922D01*
X1992364Y680380D01*
X1993237Y681255D01*
X1994547Y681546D01*
X1995857Y681255D01*
X1997167Y680380D01*
G01X2008772Y677755D02*
X2015759D01*
X2015104Y679797D01*
X2014012Y680963D01*
X2012484Y681546D01*
X2010955Y681255D01*
X2009645Y680380D01*
X2008772Y678338D01*
X2008335Y676588D01*
Y674838D01*
X2008772Y673088D01*
X2009864Y671338D01*
X2011174Y670172D01*
X2012702Y669880D01*
X2014230Y670463D01*
X2015759Y672213D01*
G01X2033477Y687380D02*
Y669880D01*
G01Y672504D02*
X2032604Y671046D01*
X2031293Y670172D01*
X2029765Y669880D01*
X2028019Y670463D01*
X2026709Y671921D01*
X2025835Y673671D01*
X2025617Y675713D01*
X2025835Y677755D01*
X2026709Y679505D01*
X2028019Y680963D01*
X2029765Y681546D01*
X2031293Y681255D01*
X2032385Y680671D01*
X2033477Y679505D01*
G01X3937Y0D02*
X116260D01*
G01X0Y3937D02*
G03X3937Y0I3937J0D01*
G01X0Y723480D02*
Y3937D01*
G01X416Y725241D02*
G03X0Y723480I3521J-1761D01*
G01X18597Y761603D02*
X416Y725241D01*
G01X77756Y98425D02*
G03X63976I-6890J0D01*
G01D02*
G03X77756I6890J0D01*
G01X83071Y245079D02*
G03Y231693I0J-6693D01*
G01X77756Y472441D02*
G03X63976I-6890J0D01*
G01D02*
G03X77756I6890J0D01*
G01X57087Y740157D02*
G03X41339I-7874J0D01*
G01D02*
G03X57087I7874J0D01*
G01X22118Y763780D02*
G03X18597Y761603I1J-3937D01*
G01X386149Y763780D02*
X22118D01*
G01X128071Y3937D02*
G03X132008Y0I3937J0D01*
G01X116260D02*
G03X120197Y3937I0J3937D01*
G01X132008Y0D02*
X275709D01*
G01X120197Y3937D02*
Y429331D01*
G01X128071Y59055D02*
Y3937D01*
G01Y59055D02*
G03X120197I-3937J0D01*
G01X128071D02*
G03X120197I-3937J0D01*
G01X128071Y98425D02*
Y421457D01*
G01X120197Y98425D02*
G03X128071I3937J0D01*
G01X120197D02*
G03X128071I3937J0D01*
G01X96457Y231693D02*
G03Y245079I0J6693D01*
G01X83071D02*
X96457D01*
G01Y231693D02*
X83071D01*
G01X96654Y413583D02*
G03X83661I-6496J0D01*
G01D02*
G03X96654I6496J0D01*
G01X132008Y425394D02*
G03X128071Y421457I0J-3937D01*
G01X124134Y433268D02*
X283583D01*
G01X124134D02*
G03X120197Y429331I0J-3937D01*
G01X184173Y425394D02*
X132008D01*
G01X213480Y37075D02*
G03I-4291J0D01*
G01Y383483D02*
G03I-4291J0D01*
G01X184173Y425394D02*
G03Y433268I0J3937D01*
G01Y425394D02*
G03Y433268I0J3937D01*
G01X171457Y669291D02*
G03X154921I-8268J0D01*
G01D02*
G03X171457I8268J0D01*
G01X223543Y425394D02*
X275709D01*
G01X223543Y433268D02*
G03Y425394I0J-3937D01*
G01Y433268D02*
G03Y425394I0J-3937D01*
G01X275709Y0D02*
G03X279646Y3937I0J3937D01*
G01X291457Y0D02*
X921260D01*
G01X287520Y3937D02*
G03X291457Y0I3937J0D01*
G01X287520Y429331D02*
Y3937D01*
G01X279646Y59055D02*
Y3937D01*
G01X287520Y59055D02*
G03X279646I-3937J0D01*
G01X287520D02*
G03X279646I-3937J0D01*
G01Y98425D02*
Y421457D01*
G01Y98425D02*
G03X287520I3937J0D01*
G01X279646D02*
G03X287520I3937J0D01*
G01X315551Y157677D02*
G03X302559I-6496J0D01*
G01D02*
G03X315551I6496J0D01*
G01X315945Y406890D02*
G03Y420276I0J6693D01*
G01X302559D02*
X315945D01*
G01X302559D02*
G03Y406890I0J-6693D01*
G01X315945D02*
X302559D01*
G01X279646Y421457D02*
G03X275709Y425394I-3937J0D01*
G01X287520Y429331D02*
G03X283583Y433268I-3937J0D01*
G01X321850Y472441D02*
G03X308071I-6889J0D01*
G01D02*
G03X321850I6889J0D01*
G01X412402Y39370D02*
G03X398622I-6890J0D01*
G01D02*
G03X412402I6890J0D01*
G01X371063Y740157D02*
G03X357283I-6890J0D01*
G01D02*
G03X371063I6890J0D01*
G01X403756Y763780D02*
G03X400235Y758082I0J-3937D01*
G01X389671Y761603D02*
G03X386149Y763780I-3522J-1760D01*
G01X414895Y728762D02*
X400235Y758082D01*
G01X407852Y725241D02*
X389671Y761603D01*
G01X403756Y763780D02*
X428096D01*
G01X416142Y200787D02*
G03X420079Y196850I3937J0D01*
G01X408268Y188976D02*
Y723480D01*
G01Y188976D02*
G03X412205I1968J0D01*
G01X556299Y196850D02*
X420079D01*
G01X564173Y188976D02*
X412205D01*
G01X416142Y316929D02*
Y200787D01*
G01Y316929D02*
G03X408268I-3937J0D01*
G01X416142D02*
G03X408268I-3937J0D01*
G01X416142Y347638D02*
Y690803D01*
G01X408268Y347638D02*
G03X416142I3937J0D01*
G01X408268D02*
G03X416142I3937J0D01*
G01Y721512D02*
Y723481D01*
G01Y723482D02*
G03X414894Y728764I-11811J-2D01*
G01X408268Y723480D02*
G03X407852Y725241I-3937J0D01*
G01X408268Y721512D02*
G03X416142I3937J0D01*
G01Y690803D02*
G03X408268I-3937J0D01*
G01Y721512D02*
G03X416142I3937J0D01*
G01Y690803D02*
G03X408268I-3937J0D01*
G01X428096Y763780D02*
G03X435970I3937J0D01*
G01D02*
X572622D01*
G01X483800Y137224D02*
G03X493878I5039J0D01*
G01X493563Y164744D02*
G03X484115I-4724J0D01*
G01D02*
G03X493563I4724J0D01*
G01X493878Y137224D02*
G03X483800I-5039J0D01*
G01X493622Y245605D02*
G03I-4291J0D01*
G01Y698924D02*
G03I-4291J0D01*
G01X556299Y196850D02*
G03X560236Y200787I0J3937D01*
G01X564173Y188976D02*
G03X568110I1968J0D01*
G01Y723480D02*
Y188976D01*
G01X560236Y316929D02*
Y200787D01*
G01X568110Y316929D02*
G03X560236I-3937J0D01*
G01X568110D02*
G03X560236I-3937J0D01*
G01Y690803D02*
Y347638D01*
G01D02*
G03X568110I3937J0D01*
G01X560236D02*
G03X568110I3937J0D01*
G01X560236Y721512D02*
Y723481D01*
G01X561484Y728764D02*
G03X560236Y723482I10563J-5284D01*
G01X568526Y725241D02*
G03X568110Y723480I3521J-1761D01*
G01X560236Y721512D02*
G03X568110I3937J0D01*
G01Y690803D02*
G03X560236I-3937J0D01*
G01Y721512D02*
G03X568110I3937J0D01*
G01Y690803D02*
G03X560236I-3937J0D01*
G01X576143Y758082D02*
G03X572622Y763780I-3521J1761D01*
G01X576143Y758082D02*
X561483Y728762D01*
G01X586707Y761603D02*
X568526Y725241D01*
G01X590228Y763780D02*
G03X586707Y761603I1J-3937D01*
G01X903079Y763780D02*
X590228D01*
G01X634252Y57874D02*
G03X625591I-4331J0D01*
G01D02*
G03X634252I4331J0D01*
G01X658661Y180000D02*
G03X646850I-5905J0D01*
G01D02*
G03X658661I5906J0D01*
G01X619094Y433071D02*
G03X605315I-6889J0D01*
G01D02*
G03X619094I6890J0D01*
G01Y740157D02*
G03X605315I-6889J0D01*
G01D02*
G03X619094I6890J0D01*
G01X712992Y57874D02*
G03X704331I-4331J0D01*
G01D02*
G03X712992I4330J0D01*
G01X859449Y332598D02*
G03X871260I5905J0D01*
G01D02*
G03X859449I-5906J0D01*
G01X921260Y0D02*
G03X925197Y3937I0J3937D01*
G01X883858Y59055D02*
G03X868110I-7874J0D01*
G01D02*
G03X883858I7874J0D01*
G01X925197Y3937D02*
Y723480D01*
G01X882874Y433071D02*
G03X869094I-6890J0D01*
G01D02*
G03X882874I6890J0D01*
G01X925197Y723480D02*
G03X924781Y725241I-3937J0D01*
G01X882874Y740157D02*
G03X869094I-6890J0D01*
G01D02*
G03X882874I6890J0D01*
G01X906600Y761603D02*
G03X903079Y763780I-3522J-1760D01*
G01X924781Y725241D02*
X906600Y761603D01*
G54D13*
G01X339800Y524788D02*
Y528599D01*
G01X337237Y522225D02*
X339800Y524788D01*
G01X338537Y521686D02*
X341100Y524249D01*
G01X337237Y507876D02*
Y522225D01*
G01X338537Y508415D02*
Y521686D01*
G01X338675Y506438D02*
X337237Y507876D01*
G01X339975Y506977D02*
X338537Y508415D01*
G01X338675Y489782D02*
Y506438D01*
G01X339975Y490321D02*
Y506977D01*
G01X342725Y485732D02*
X338675Y489782D01*
G01X344025Y486271D02*
X339975Y490321D01*
G01X339800Y524788D02*
Y528599D01*
G01X338537Y521686D02*
X341100Y524249D01*
G01X337237Y522225D02*
X339800Y524788D01*
G01X338537Y508415D02*
Y521686D01*
G01X337237Y507876D02*
Y522225D01*
G01X339975Y506977D02*
X338537Y508415D01*
G01X338675Y506438D02*
X337237Y507876D01*
G01X339975Y490321D02*
Y506977D01*
G01X338675Y489782D02*
Y506438D01*
G01X344025Y486271D02*
X339975Y490321D01*
G01X342725Y485732D02*
X338675Y489782D01*
G01X339826Y590941D02*
X344825Y595940D01*
G01X339826Y579166D02*
Y590941D01*
G01X336555Y575895D02*
X339826Y579166D01*
G01X337855Y575356D02*
X341126Y578627D01*
G01X336555Y565698D02*
Y575895D01*
G01X337855Y566237D02*
Y575356D01*
G01X338490Y563763D02*
X336555Y565698D01*
G01X339790Y564302D02*
X337855Y566237D01*
G01X338490Y551398D02*
Y563763D01*
G01X339790Y551937D02*
Y564302D01*
G01X343794Y546094D02*
X338490Y551398D01*
G01X345094Y546633D02*
X339790Y551937D01*
G01X339800Y528599D02*
X343794Y532593D01*
G01X339826Y590941D02*
X344825Y595940D01*
G01X339826Y579166D02*
Y590941D01*
G01X337855Y575356D02*
X341126Y578627D01*
G01X336555Y575895D02*
X339826Y579166D01*
G01X337855Y566237D02*
Y575356D01*
G01X336555Y565698D02*
Y575895D01*
G01X339790Y564302D02*
X337855Y566237D01*
G01X338490Y563763D02*
X336555Y565698D01*
G01X339790Y551937D02*
Y564302D01*
G01X338490Y551398D02*
Y563763D01*
G01X345094Y546633D02*
X339790Y551937D01*
G01X343794Y546094D02*
X338490Y551398D01*
G01X339800Y528599D02*
X343794Y532593D01*
G01X356920Y107733D02*
Y172071D01*
G01X358220Y108272D02*
Y147260D01*
G01X371297Y93356D02*
X356920Y107733D01*
G01X372597Y93895D02*
X358220Y108272D01*
G01X371297Y84639D02*
Y93356D01*
G01X372597Y85178D02*
Y93895D01*
G01X381432Y74504D02*
X371297Y84639D01*
G01X373764Y84011D02*
X372597Y85178D01*
G01X374754Y84011D02*
X373764D01*
G01X377087Y80688D02*
X375920Y81855D01*
G01X378133Y80688D02*
X377087D01*
G01X381971Y75804D02*
X379300Y78475D01*
G01X387605Y74504D02*
X381432D01*
G01X387066Y75804D02*
X381971D01*
G01X389352Y76251D02*
X387605Y74504D01*
G01X388052Y76790D02*
X387066Y75804D01*
G01X389352Y78589D02*
Y76251D01*
G01X388052Y78400D02*
Y76790D01*
G01X356920Y107733D02*
Y172071D01*
G01Y107733D02*
Y172071D01*
G01Y107733D02*
Y172071D01*
G01Y107733D02*
Y172071D01*
G01X358220Y108272D02*
Y147260D01*
G01X356920Y107733D02*
Y172071D01*
G01X372597Y93895D02*
X358220Y108272D01*
G01X371297Y93356D02*
X356920Y107733D01*
G01X372597Y85178D02*
Y93895D01*
G01X371297Y84639D02*
Y93356D01*
G01X373764Y84011D02*
X372597Y85178D01*
G01X381432Y74504D02*
X371297Y84639D01*
G01X374754Y84011D02*
X373764D01*
G01X381432Y74504D02*
X371297Y84639D01*
G01X377087Y80688D02*
X375920Y81855D01*
G01X381432Y74504D02*
X371297Y84639D01*
G01X378133Y80688D02*
X377087D01*
G01X381432Y74504D02*
X371297Y84639D01*
G01X381971Y75804D02*
X379300Y78475D01*
G01X381432Y74504D02*
X371297Y84639D01*
G01X387066Y75804D02*
X381971D01*
G01X387605Y74504D02*
X381432D01*
G01X388052Y76790D02*
X387066Y75804D01*
G01X389352Y76251D02*
X387605Y74504D01*
G01X388052Y78400D02*
Y76790D01*
G01X389352Y78589D02*
Y76251D01*
G01X353447Y197114D02*
X350878Y199683D01*
G01X354747Y197653D02*
X352178Y200222D01*
G01X353447Y175544D02*
Y197114D01*
G01X354747Y176083D02*
Y197653D01*
G01X356920Y172071D02*
X353447Y175544D01*
G01X358220Y172610D02*
X354747Y176083D01*
G01X358220Y164410D02*
Y172610D01*
G01Y159710D02*
Y161360D01*
G01Y155010D02*
Y156660D01*
G01Y150310D02*
Y151960D01*
G01X354747Y197653D02*
X352178Y200222D01*
G01X353447Y197114D02*
X350878Y199683D01*
G01X354747Y176083D02*
Y197653D01*
G01X353447Y175544D02*
Y197114D01*
G01X358220Y172610D02*
X354747Y176083D01*
G01X356920Y172071D02*
X353447Y175544D01*
G01X358220Y164410D02*
Y172610D01*
G01Y159710D02*
Y161360D01*
G01Y155010D02*
Y156660D01*
G01Y150310D02*
Y151960D01*
G01X357333Y248118D02*
Y435842D01*
G01X358633Y247579D02*
Y436381D01*
G01X350878Y241663D02*
X357333Y248118D01*
G01X352178Y241124D02*
X358633Y247579D01*
G01X350878Y199683D02*
Y241663D01*
G01X352178Y223331D02*
Y241124D01*
G01Y218631D02*
Y220281D01*
G01Y213931D02*
Y215581D01*
G01Y200222D02*
Y210881D01*
G01X358633Y247579D02*
Y436381D01*
G01X357333Y248118D02*
Y435842D01*
G01X352178Y241124D02*
X358633Y247579D01*
G01X350878Y241663D02*
X357333Y248118D01*
G01X352178Y223331D02*
Y241124D01*
G01X350878Y199683D02*
Y241663D01*
G01X352178Y218631D02*
Y220281D01*
G01X350878Y199683D02*
Y241663D01*
G01X352178Y213931D02*
Y215581D01*
G01X350878Y199683D02*
Y241663D01*
G01X352178Y200222D02*
Y210881D01*
G01X350878Y199683D02*
Y241663D01*
G01X342725Y450450D02*
Y485732D01*
G01X344025Y450989D02*
Y486271D01*
G01X357333Y435842D02*
X342725Y450450D01*
G01X358633Y436381D02*
X344025Y450989D01*
G01D02*
Y486271D01*
G01X342725Y450450D02*
Y485732D01*
G01X358633Y436381D02*
X344025Y450989D01*
G01X357333Y435842D02*
X342725Y450450D01*
G01X341100Y524249D02*
Y528060D01*
G01Y524249D02*
Y528060D01*
G01X341126Y590402D02*
X346125Y595401D01*
G01X341126Y578627D02*
Y590402D01*
G01X343794Y532593D02*
Y546094D01*
G01X345094Y532054D02*
Y546633D01*
G01X341100Y528060D02*
X345094Y532054D01*
G01X341126Y590402D02*
X346125Y595401D01*
G01X341126Y578627D02*
Y590402D01*
G01X345094Y532054D02*
Y546633D01*
G01X343794Y532593D02*
Y546094D01*
G01X341100Y528060D02*
X345094Y532054D01*
G01X341320Y623245D02*
Y630197D01*
G01X342620Y623784D02*
Y630240D01*
G01X344825Y619740D02*
X341320Y623245D01*
G01X346125Y620279D02*
X342620Y623784D01*
G01X344825Y595940D02*
Y619740D01*
G01X346125Y609501D02*
Y620279D01*
G01Y604801D02*
Y606451D01*
G01Y600101D02*
Y601751D01*
G01Y595401D02*
Y597051D01*
G01X342620Y623784D02*
Y630240D01*
G01X341320Y623245D02*
Y630197D01*
G01X346125Y620279D02*
X342620Y623784D01*
G01X344825Y619740D02*
X341320Y623245D01*
G01X346125Y609501D02*
Y620279D01*
G01X344825Y595940D02*
Y619740D01*
G01X346125Y604801D02*
Y606451D01*
G01X344825Y595940D02*
Y619740D01*
G01X346125Y600101D02*
Y601751D01*
G01X344825Y595940D02*
Y619740D01*
G01X346125Y595401D02*
Y597051D01*
G01X344825Y595940D02*
Y619740D01*
M02*
